(kicad_pcb
	(version 20260206)
	(generator "pcbnew")
	(generator_version "10.0")
	(general
		(thickness 1.6)
		(legacy_teardrops no)
	)
	(paper "A4")
	(title_block
		(title "03242023_DA0F0TMBIJ0_F0T_Motherboard_J_brd_V01_OCP.brd")
		(comment 1 "Grand Teton / footprints 4249-4256 of 6105")
	)
	(layers
		(0 "F.Cu" signal "TOP")
		(4 "In1.Cu" signal "GND")
		(6 "In2.Cu" signal "IN1")
		(8 "In3.Cu" signal "GND1")
		(10 "In4.Cu" signal "IN2")
		(12 "In5.Cu" signal "GND2")
		(14 "In6.Cu" signal "IN3")
		(16 "In7.Cu" signal "GND3")
		(18 "In8.Cu" signal "VCC")
		(20 "In9.Cu" signal "VCC1")
		(22 "In10.Cu" signal "GND4")
		(24 "In11.Cu" signal "IN4")
		(26 "In12.Cu" signal "GND5")
		(28 "In13.Cu" signal "IN5")
		(30 "In14.Cu" signal "GND6")
		(32 "In15.Cu" signal "IN6")
		(34 "In16.Cu" signal "GND7")
		(2 "B.Cu" signal "BOTTOM")
		(9 "F.Adhes" user "F.Adhesive")
		(11 "B.Adhes" user "B.Adhesive")
		(13 "F.Paste" user "Package Geometry/Pastemask Top")
		(15 "B.Paste" user "Package Geometry/Pastemask Bottom")
		(5 "F.SilkS" user "Ref Des/Silkscreen Top")
		(7 "B.SilkS" user "Ref Des/Silkscreen Bottom")
		(1 "F.Mask" user "Board Geometry/Soldermask Top")
		(3 "B.Mask" user "Board Geometry/Soldermask Bottom")
		(17 "Dwgs.User" user "User.Drawings")
		(19 "Cmts.User" user "User.Comments")
		(21 "Eco1.User" user "User.Eco1")
		(23 "Eco2.User" user "User.Eco2")
		(25 "Edge.Cuts" user "Board Geometry/Outline")
		(27 "Margin" user)
		(31 "F.CrtYd" user "Package Geometry/Place Bound Top")
		(29 "B.CrtYd" user "Package Geometry/Place Bound Bottom")
		(35 "F.Fab" user "Ref Des/Assembly Top")
		(33 "B.Fab" user "Ref Des/Assembly Bottom")
	)
	(footprint ""
		(layer "B.Cu")
		(at 81.798414 -342.936576 90)
		(property "Reference" "PC494_P1_7"
			(at 0 0 90)
			(layer "B.SilkS")
			(hide yes)
			(effects
				(font
					(size 1.27 1.27)
				)
				(justify mirror)
			)
		)
		(property "Value" ""
			(at 0 0 90)
			(layer "B.Fab")
			(effects
				(font
					(size 1.27 1.27)
				)
				(justify mirror)
			)
		)
		(duplicate_pad_numbers_are_jumpers no)
		(fp_line
			(start 1.524 -0.762)
			(end -1.524 -0.762)
			(stroke
				(width 0.1524)
				(type default)
			)
			(layer "B.SilkS")
		)
		(fp_line
			(start -1.524 -0.762)
			(end -1.524 0.762)
			(stroke
				(width 0.1524)
				(type default)
			)
			(layer "B.SilkS")
		)
		(fp_line
			(start 1.524 0.762)
			(end 1.524 -0.762)
			(stroke
				(width 0.1524)
				(type default)
			)
			(layer "B.SilkS")
		)
		(fp_line
			(start -1.524 0.762)
			(end 1.524 0.762)
			(stroke
				(width 0.1524)
				(type default)
			)
			(layer "B.SilkS")
		)
		(fp_line
			(start 1.1049 -0.724916)
			(end 1.1049 0.724916)
			(stroke
				(width 0.1)
				(type default)
			)
			(layer "B.Fab")
		)
		(fp_line
			(start -1.1049 -0.724916)
			(end 1.1049 -0.724916)
			(stroke
				(width 0.1)
				(type default)
			)
			(layer "B.Fab")
		)
		(fp_line
			(start 1.1049 0.724916)
			(end -1.1049 0.724916)
			(stroke
				(width 0.1)
				(type default)
			)
			(layer "B.Fab")
		)
		(fp_line
			(start -1.1049 0.724916)
			(end -1.1049 -0.724916)
			(stroke
				(width 0.1)
				(type default)
			)
			(layer "B.Fab")
		)
		(pad "1" smd rect
			(at 0.889 0 90)
			(size 1.016 1.27)
			(layers "B.Cu" "B.Mask" "B.Paste")
			(net "SW_P12V_PVCCIN_CPU1_FLT")
		)
		(pad "2" smd rect
			(at -0.889 0 90)
			(size 1.016 1.27)
			(layers "B.Cu" "B.Mask" "B.Paste")
			(net "GND")
		)
	)
	(footprint ""
		(layer "B.Cu")
		(at 180.8734 -21.364448 -90)
		(property "Reference" "R3062"
			(at 0 0 90)
			(layer "B.SilkS")
			(hide yes)
			(effects
				(font
					(size 1.27 1.27)
				)
				(justify mirror)
			)
		)
		(property "Value" ""
			(at 0 0 90)
			(layer "B.Fab")
			(effects
				(font
					(size 1.27 1.27)
				)
				(justify mirror)
			)
		)
		(duplicate_pad_numbers_are_jumpers no)
		(fp_line
			(start -0.7874 0.4064)
			(end 0.7874 0.4064)
			(stroke
				(width 0.1524)
				(type default)
			)
			(layer "B.SilkS")
		)
		(fp_line
			(start 0.7874 0.4064)
			(end 0.7874 -0.4064)
			(stroke
				(width 0.1524)
				(type default)
			)
			(layer "B.SilkS")
		)
		(fp_line
			(start -0.7874 -0.4064)
			(end -0.7874 0.4064)
			(stroke
				(width 0.1524)
				(type default)
			)
			(layer "B.SilkS")
		)
		(fp_line
			(start 0.7874 -0.4064)
			(end -0.7874 -0.4064)
			(stroke
				(width 0.1524)
				(type default)
			)
			(layer "B.SilkS")
		)
		(fp_line
			(start -0.67945 0.3048)
			(end -0.120396 0.3048)
			(stroke
				(width 0.1)
				(type default)
			)
			(layer "B.Fab")
		)
		(fp_line
			(start -0.120396 0.3048)
			(end -0.120396 0.2794)
			(stroke
				(width 0.1)
				(type default)
			)
			(layer "B.Fab")
		)
		(fp_line
			(start 0.12065 0.3048)
			(end 0.67945 0.3048)
			(stroke
				(width 0.1)
				(type default)
			)
			(layer "B.Fab")
		)
		(fp_line
			(start 0.67945 0.3048)
			(end 0.67945 -0.305054)
			(stroke
				(width 0.1)
				(type default)
			)
			(layer "B.Fab")
		)
		(fp_line
			(start -0.120396 0.2794)
			(end 0.12065 0.2794)
			(stroke
				(width 0.1)
				(type default)
			)
			(layer "B.Fab")
		)
		(fp_line
			(start 0.12065 0.2794)
			(end 0.12065 0.3048)
			(stroke
				(width 0.1)
				(type default)
			)
			(layer "B.Fab")
		)
		(fp_line
			(start -0.12065 -0.2794)
			(end -0.12065 -0.3048)
			(stroke
				(width 0.1)
				(type default)
			)
			(layer "B.Fab")
		)
		(fp_line
			(start 0.12065 -0.2794)
			(end -0.12065 -0.2794)
			(stroke
				(width 0.1)
				(type default)
			)
			(layer "B.Fab")
		)
		(fp_line
			(start -0.67945 -0.3048)
			(end -0.67945 0.3048)
			(stroke
				(width 0.1)
				(type default)
			)
			(layer "B.Fab")
		)
		(fp_line
			(start -0.12065 -0.3048)
			(end -0.67945 -0.3048)
			(stroke
				(width 0.1)
				(type default)
			)
			(layer "B.Fab")
		)
		(fp_line
			(start 0.12065 -0.305054)
			(end 0.12065 -0.2794)
			(stroke
				(width 0.1)
				(type default)
			)
			(layer "B.Fab")
		)
		(fp_line
			(start 0.67945 -0.305054)
			(end 0.12065 -0.305054)
			(stroke
				(width 0.1)
				(type default)
			)
			(layer "B.Fab")
		)
		(pad "1" smd circle
			(at 0.40005 0 90)
			(size 0 0)
			(layers "B.Cu" "B.Mask" "B.Paste")
			(net "SMB_HOST_3V3AUX_SDA")
		)
		(pad "2" smd circle
			(at -0.40005 0 90)
			(size 0 0)
			(layers "B.Cu" "B.Mask" "B.Paste")
			(net "P3V3_AUX")
		)
	)
	(footprint ""
		(layer "B.Cu")
		(at 438.4802 -434.365908)
		(property "Reference" ""
			(at 0 0 0)
			(layer "B.SilkS")
			(hide yes)
			(effects
				(font
					(size 1.27 1.27)
				)
				(justify mirror)
			)
		)
		(property "Value" ""
			(at 0 0 0)
			(layer "B.Fab")
			(effects
				(font
					(size 1.27 1.27)
				)
				(justify mirror)
			)
		)
		(duplicate_pad_numbers_are_jumpers no)
		(pad "1" smd circle
			(at 0 0 180)
			(size 0.9906 0.9906)
			(layers "B.Cu" "B.Mask" "B.Paste")
			(net "Net_287")
		)
		(zone
			(layer "B.Cu")
			(hatch none 0.5)
			(connect_pads
				(clearance 0)
			)
			(min_thickness 0.25)
			(keepout
				(tracks not_allowed)
				(vias allowed)
				(pads allowed)
				(copperpour not_allowed)
				(footprints allowed)
			)
			(placement
				(enabled no)
				(sheetname "")
			)
			(fill
				(thermal_gap 0.5)
				(thermal_bridge_width 0.5)
				(island_removal_mode 0)
			)
			(polygon
				(pts
					(arc
						(start 440.1058 -434.365908)
						(mid 436.8546 -434.365908)
						(end 440.1058 -434.365908)
					)
				)
			)
		)
	)
	(footprint ""
		(layer "B.Cu")
		(at 30.163516 -130.297682 180)
		(property "Reference" "PC1292"
			(at 0 0 0)
			(layer "B.SilkS")
			(hide yes)
			(effects
				(font
					(size 1.27 1.27)
				)
				(justify mirror)
			)
		)
		(property "Value" ""
			(at 0 0 0)
			(layer "B.Fab")
			(effects
				(font
					(size 1.27 1.27)
				)
				(justify mirror)
			)
		)
		(duplicate_pad_numbers_are_jumpers no)
		(fp_line
			(start 0.7874 0.4064)
			(end 0.7874 -0.4064)
			(stroke
				(width 0.1524)
				(type default)
			)
			(layer "B.SilkS")
		)
		(fp_line
			(start 0.7874 -0.4064)
			(end -0.7874 -0.4064)
			(stroke
				(width 0.1524)
				(type default)
			)
			(layer "B.SilkS")
		)
		(fp_line
			(start -0.7874 0.4064)
			(end 0.7874 0.4064)
			(stroke
				(width 0.1524)
				(type default)
			)
			(layer "B.SilkS")
		)
		(fp_line
			(start -0.7874 -0.4064)
			(end -0.7874 0.4064)
			(stroke
				(width 0.1524)
				(type default)
			)
			(layer "B.SilkS")
		)
		(fp_line
			(start 0.67945 0.3048)
			(end 0.67945 -0.305054)
			(stroke
				(width 0.1)
				(type default)
			)
			(layer "B.Fab")
		)
		(fp_line
			(start 0.67945 -0.305054)
			(end 0.12065 -0.305054)
			(stroke
				(width 0.1)
				(type default)
			)
			(layer "B.Fab")
		)
		(fp_line
			(start 0.12065 0.3048)
			(end 0.67945 0.3048)
			(stroke
				(width 0.1)
				(type default)
			)
			(layer "B.Fab")
		)
		(fp_line
			(start 0.12065 0.2794)
			(end 0.12065 0.3048)
			(stroke
				(width 0.1)
				(type default)
			)
			(layer "B.Fab")
		)
		(fp_line
			(start 0.12065 -0.2794)
			(end -0.12065 -0.2794)
			(stroke
				(width 0.1)
				(type default)
			)
			(layer "B.Fab")
		)
		(fp_line
			(start 0.12065 -0.305054)
			(end 0.12065 -0.2794)
			(stroke
				(width 0.1)
				(type default)
			)
			(layer "B.Fab")
		)
		(fp_line
			(start -0.120396 0.3048)
			(end -0.120396 0.2794)
			(stroke
				(width 0.1)
				(type default)
			)
			(layer "B.Fab")
		)
		(fp_line
			(start -0.120396 0.2794)
			(end 0.12065 0.2794)
			(stroke
				(width 0.1)
				(type default)
			)
			(layer "B.Fab")
		)
		(fp_line
			(start -0.12065 -0.2794)
			(end -0.12065 -0.3048)
			(stroke
				(width 0.1)
				(type default)
			)
			(layer "B.Fab")
		)
		(fp_line
			(start -0.12065 -0.3048)
			(end -0.67945 -0.3048)
			(stroke
				(width 0.1)
				(type default)
			)
			(layer "B.Fab")
		)
		(fp_line
			(start -0.67945 0.3048)
			(end -0.120396 0.3048)
			(stroke
				(width 0.1)
				(type default)
			)
			(layer "B.Fab")
		)
		(fp_line
			(start -0.67945 -0.3048)
			(end -0.67945 0.3048)
			(stroke
				(width 0.1)
				(type default)
			)
			(layer "B.Fab")
		)
		(pad "1" smd circle
			(at 0.40005 0)
			(size 0 0)
			(layers "B.Cu" "B.Mask" "B.Paste")
			(net "PVCCFA_EHV_CPU1_BTSEN")
		)
		(pad "2" smd circle
			(at -0.40005 0)
			(size 0 0)
			(layers "B.Cu" "B.Mask" "B.Paste")
			(net "GND")
		)
	)
	(footprint ""
		(layer "B.Cu")
		(at 12.217146 -321.554856 -90)
		(property "Reference" "C69"
			(at 0 0 90)
			(layer "B.SilkS")
			(hide yes)
			(effects
				(font
					(size 1.27 1.27)
				)
				(justify mirror)
			)
		)
		(property "Value" ""
			(at 0 0 90)
			(layer "B.Fab")
			(effects
				(font
					(size 1.27 1.27)
				)
				(justify mirror)
			)
		)
		(duplicate_pad_numbers_are_jumpers no)
		(fp_line
			(start -1.524 0.762)
			(end 1.524 0.762)
			(stroke
				(width 0.1524)
				(type default)
			)
			(layer "B.SilkS")
		)
		(fp_line
			(start 1.524 0.762)
			(end 1.524 -0.762)
			(stroke
				(width 0.1524)
				(type default)
			)
			(layer "B.SilkS")
		)
		(fp_line
			(start -1.524 -0.762)
			(end -1.524 0.762)
			(stroke
				(width 0.1524)
				(type default)
			)
			(layer "B.SilkS")
		)
		(fp_line
			(start 1.524 -0.762)
			(end -1.524 -0.762)
			(stroke
				(width 0.1524)
				(type default)
			)
			(layer "B.SilkS")
		)
		(fp_line
			(start -1.1049 0.724916)
			(end -1.1049 -0.724916)
			(stroke
				(width 0.1)
				(type default)
			)
			(layer "B.Fab")
		)
		(fp_line
			(start 1.1049 0.724916)
			(end -1.1049 0.724916)
			(stroke
				(width 0.1)
				(type default)
			)
			(layer "B.Fab")
		)
		(fp_line
			(start -1.1049 -0.724916)
			(end 1.1049 -0.724916)
			(stroke
				(width 0.1)
				(type default)
			)
			(layer "B.Fab")
		)
		(fp_line
			(start 1.1049 -0.724916)
			(end 1.1049 0.724916)
			(stroke
				(width 0.1)
				(type default)
			)
			(layer "B.Fab")
		)
		(pad "1" smd rect
			(at 0.889 0 270)
			(size 1.016 1.27)
			(layers "B.Cu" "B.Mask" "B.Paste")
			(net "P12V_S3_AUX_CPU1_NVDIMM")
		)
		(pad "2" smd rect
			(at -0.889 0 270)
			(size 1.016 1.27)
			(layers "B.Cu" "B.Mask" "B.Paste")
			(net "GND")
		)
	)
	(footprint ""
		(layer "B.Cu")
		(at 364.342934 -237.717838 90)
		(property "Reference" "C363"
			(at 0 0 90)
			(layer "B.SilkS")
			(hide yes)
			(effects
				(font
					(size 1.27 1.27)
				)
				(justify mirror)
			)
		)
		(property "Value" ""
			(at 0 0 90)
			(layer "B.Fab")
			(effects
				(font
					(size 1.27 1.27)
				)
				(justify mirror)
			)
		)
		(duplicate_pad_numbers_are_jumpers no)
		(fp_line
			(start 1.524 -0.762)
			(end -1.524 -0.762)
			(stroke
				(width 0.1524)
				(type default)
			)
			(layer "B.SilkS")
		)
		(fp_line
			(start -1.524 -0.762)
			(end -1.524 0.762)
			(stroke
				(width 0.1524)
				(type default)
			)
			(layer "B.SilkS")
		)
		(fp_line
			(start 1.524 0.762)
			(end 1.524 -0.762)
			(stroke
				(width 0.1524)
				(type default)
			)
			(layer "B.SilkS")
		)
		(fp_line
			(start -1.524 0.762)
			(end 1.524 0.762)
			(stroke
				(width 0.1524)
				(type default)
			)
			(layer "B.SilkS")
		)
		(fp_line
			(start 1.1049 -0.724916)
			(end 1.1049 0.724916)
			(stroke
				(width 0.1)
				(type default)
			)
			(layer "B.Fab")
		)
		(fp_line
			(start -1.1049 -0.724916)
			(end 1.1049 -0.724916)
			(stroke
				(width 0.1)
				(type default)
			)
			(layer "B.Fab")
		)
		(fp_line
			(start 1.1049 0.724916)
			(end -1.1049 0.724916)
			(stroke
				(width 0.1)
				(type default)
			)
			(layer "B.Fab")
		)
		(fp_line
			(start -1.1049 0.724916)
			(end -1.1049 -0.724916)
			(stroke
				(width 0.1)
				(type default)
			)
			(layer "B.Fab")
		)
		(pad "1" smd rect
			(at 0.889 0 90)
			(size 1.016 1.27)
			(layers "B.Cu" "B.Mask" "B.Paste")
			(net "PVCCIN_CPU0")
		)
		(pad "2" smd rect
			(at -0.889 0 90)
			(size 1.016 1.27)
			(layers "B.Cu" "B.Mask" "B.Paste")
			(net "GND")
		)
	)
	(footprint ""
		(layer "B.Cu")
		(at 254.824484 -107.361228 180)
		(property "Reference" "R1267"
			(at 0 0 0)
			(layer "B.SilkS")
			(hide yes)
			(effects
				(font
					(size 1.27 1.27)
				)
				(justify mirror)
			)
		)
		(property "Value" ""
			(at 0 0 0)
			(layer "B.Fab")
			(effects
				(font
					(size 1.27 1.27)
				)
				(justify mirror)
			)
		)
		(duplicate_pad_numbers_are_jumpers no)
		(fp_line
			(start 0.7874 0.4064)
			(end 0.7874 -0.4064)
			(stroke
				(width 0.1524)
				(type default)
			)
			(layer "B.SilkS")
		)
		(fp_line
			(start 0.7874 -0.4064)
			(end -0.7874 -0.4064)
			(stroke
				(width 0.1524)
				(type default)
			)
			(layer "B.SilkS")
		)
		(fp_line
			(start -0.7874 0.4064)
			(end 0.7874 0.4064)
			(stroke
				(width 0.1524)
				(type default)
			)
			(layer "B.SilkS")
		)
		(fp_line
			(start -0.7874 -0.4064)
			(end -0.7874 0.4064)
			(stroke
				(width 0.1524)
				(type default)
			)
			(layer "B.SilkS")
		)
		(fp_line
			(start 0.67945 0.3048)
			(end 0.67945 -0.305054)
			(stroke
				(width 0.1)
				(type default)
			)
			(layer "B.Fab")
		)
		(fp_line
			(start 0.67945 -0.305054)
			(end 0.12065 -0.305054)
			(stroke
				(width 0.1)
				(type default)
			)
			(layer "B.Fab")
		)
		(fp_line
			(start 0.12065 0.3048)
			(end 0.67945 0.3048)
			(stroke
				(width 0.1)
				(type default)
			)
			(layer "B.Fab")
		)
		(fp_line
			(start 0.12065 0.2794)
			(end 0.12065 0.3048)
			(stroke
				(width 0.1)
				(type default)
			)
			(layer "B.Fab")
		)
		(fp_line
			(start 0.12065 -0.2794)
			(end -0.12065 -0.2794)
			(stroke
				(width 0.1)
				(type default)
			)
			(layer "B.Fab")
		)
		(fp_line
			(start 0.12065 -0.305054)
			(end 0.12065 -0.2794)
			(stroke
				(width 0.1)
				(type default)
			)
			(layer "B.Fab")
		)
		(fp_line
			(start -0.120396 0.3048)
			(end -0.120396 0.2794)
			(stroke
				(width 0.1)
				(type default)
			)
			(layer "B.Fab")
		)
		(fp_line
			(start -0.120396 0.2794)
			(end 0.12065 0.2794)
			(stroke
				(width 0.1)
				(type default)
			)
			(layer "B.Fab")
		)
		(fp_line
			(start -0.12065 -0.2794)
			(end -0.12065 -0.3048)
			(stroke
				(width 0.1)
				(type default)
			)
			(layer "B.Fab")
		)
		(fp_line
			(start -0.12065 -0.3048)
			(end -0.67945 -0.3048)
			(stroke
				(width 0.1)
				(type default)
			)
			(layer "B.Fab")
		)
		(fp_line
			(start -0.67945 0.3048)
			(end -0.120396 0.3048)
			(stroke
				(width 0.1)
				(type default)
			)
			(layer "B.Fab")
		)
		(fp_line
			(start -0.67945 -0.3048)
			(end -0.67945 0.3048)
			(stroke
				(width 0.1)
				(type default)
			)
			(layer "B.Fab")
		)
		(pad "1" smd circle
			(at 0.40005 0)
			(size 0 0)
			(layers "B.Cu" "B.Mask" "B.Paste")
			(net "PU_CK440_SHFT_LD_N")
		)
		(pad "2" smd circle
			(at -0.40005 0)
			(size 0 0)
			(layers "B.Cu" "B.Mask" "B.Paste")
			(net "GND")
		)
	)
	(footprint ""
		(layer "B.Cu")
		(at 60.926218 -319.393824 180)
		(property "Reference" "C53"
			(at 0 0 0)
			(layer "B.SilkS")
			(hide yes)
			(effects
				(font
					(size 1.27 1.27)
				)
				(justify mirror)
			)
		)
		(property "Value" ""
			(at 0 0 0)
			(layer "B.Fab")
			(effects
				(font
					(size 1.27 1.27)
				)
				(justify mirror)
			)
		)
		(duplicate_pad_numbers_are_jumpers no)
		(fp_line
			(start 0.7874 0.4064)
			(end 0.7874 -0.4064)
			(stroke
				(width 0.1524)
				(type default)
			)
			(layer "B.SilkS")
		)
		(fp_line
			(start 0.7874 -0.4064)
			(end -0.7874 -0.4064)
			(stroke
				(width 0.1524)
				(type default)
			)
			(layer "B.SilkS")
		)
		(fp_line
			(start -0.7874 0.4064)
			(end 0.7874 0.4064)
			(stroke
				(width 0.1524)
				(type default)
			)
			(layer "B.SilkS")
		)
		(fp_line
			(start -0.7874 -0.4064)
			(end -0.7874 0.4064)
			(stroke
				(width 0.1524)
				(type default)
			)
			(layer "B.SilkS")
		)
		(fp_line
			(start 0.67945 0.3048)
			(end 0.67945 -0.305054)
			(stroke
				(width 0.1)
				(type default)
			)
			(layer "B.Fab")
		)
		(fp_line
			(start 0.67945 -0.305054)
			(end 0.12065 -0.305054)
			(stroke
				(width 0.1)
				(type default)
			)
			(layer "B.Fab")
		)
		(fp_line
			(start 0.12065 0.3048)
			(end 0.67945 0.3048)
			(stroke
				(width 0.1)
				(type default)
			)
			(layer "B.Fab")
		)
		(fp_line
			(start 0.12065 0.2794)
			(end 0.12065 0.3048)
			(stroke
				(width 0.1)
				(type default)
			)
			(layer "B.Fab")
		)
		(fp_line
			(start 0.12065 -0.2794)
			(end -0.12065 -0.2794)
			(stroke
				(width 0.1)
				(type default)
			)
			(layer "B.Fab")
		)
		(fp_line
			(start 0.12065 -0.305054)
			(end 0.12065 -0.2794)
			(stroke
				(width 0.1)
				(type default)
			)
			(layer "B.Fab")
		)
		(fp_line
			(start -0.120396 0.3048)
			(end -0.120396 0.2794)
			(stroke
				(width 0.1)
				(type default)
			)
			(layer "B.Fab")
		)
		(fp_line
			(start -0.120396 0.2794)
			(end 0.12065 0.2794)
			(stroke
				(width 0.1)
				(type default)
			)
			(layer "B.Fab")
		)
		(fp_line
			(start -0.12065 -0.2794)
			(end -0.12065 -0.3048)
			(stroke
				(width 0.1)
				(type default)
			)
			(layer "B.Fab")
		)
		(fp_line
			(start -0.12065 -0.3048)
			(end -0.67945 -0.3048)
			(stroke
				(width 0.1)
				(type default)
			)
			(layer "B.Fab")
		)
		(fp_line
			(start -0.67945 0.3048)
			(end -0.120396 0.3048)
			(stroke
				(width 0.1)
				(type default)
			)
			(layer "B.Fab")
		)
		(fp_line
			(start -0.67945 -0.3048)
			(end -0.67945 0.3048)
			(stroke
				(width 0.1)
				(type default)
			)
			(layer "B.Fab")
		)
		(pad "1" smd circle
			(at 0.40005 0)
			(size 0 0)
			(layers "B.Cu" "B.Mask" "B.Paste")
			(net "P3V3_AUX")
		)
		(pad "2" smd circle
			(at -0.40005 0)
			(size 0 0)
			(layers "B.Cu" "B.Mask" "B.Paste")
			(net "GND")
		)
	)
)
